(kicad_pcb
	(version 20260206)
	(generator "pcbnew")
	(generator_version "10.0")
	(general
		(thickness 1.6)
		(legacy_teardrops no)
	)
	(paper "A4")
	(title_block
		(title "Wiwynn_Tioga_Pass_MB.brd")
		(comment 1 "Tioga Pass / footprints 2381-2387 of 4770")
	)
	(layers
		(0 "F.Cu" signal "TOP")
		(4 "In1.Cu" signal "L2GND")
		(6 "In2.Cu" signal "L3")
		(8 "In3.Cu" signal "L4GND")
		(10 "In4.Cu" signal "L5")
		(12 "In5.Cu" signal "L6GND")
		(14 "In6.Cu" signal "L7VCC")
		(16 "In7.Cu" signal "L8VCC")
		(18 "In8.Cu" signal "L9GND")
		(20 "In9.Cu" signal "L10")
		(22 "In10.Cu" signal "L11GND")
		(24 "In11.Cu" signal "L12")
		(26 "In12.Cu" signal "L13GND")
		(2 "B.Cu" signal "BOTTOM")
		(9 "F.Adhes" user "F.Adhesive")
		(11 "B.Adhes" user "B.Adhesive")
		(13 "F.Paste" user "Package Geometry/Pastemask Top")
		(15 "B.Paste" user "Package Geometry/Pastemask Bottom")
		(5 "F.SilkS" user "Ref Des/Silkscreen Top")
		(7 "B.SilkS" user "Ref Des/Silkscreen Bottom")
		(1 "F.Mask" user "Board Geometry/Soldermask Top")
		(3 "B.Mask" user "Board Geometry/Soldermask Bottom")
		(17 "Dwgs.User" user "User.Drawings")
		(19 "Cmts.User" user "User.Comments")
		(21 "Eco1.User" user "User.Eco1")
		(23 "Eco2.User" user "User.Eco2")
		(25 "Edge.Cuts" user "Board Geometry/Outline")
		(27 "Margin" user)
		(31 "F.CrtYd" user "Package Geometry/Place Bound Top")
		(29 "B.CrtYd" user "Package Geometry/Place Bound Bottom")
		(35 "F.Fab" user "Ref Des/Assembly Top")
		(33 "B.Fab" user "Ref Des/Assembly Bottom")
	)
	(footprint ""
		(layer "B.Cu")
		(at 493.06734 -123.06808 90)
		(property "Reference" "C9B7"
			(at 0 0 90)
			(layer "B.SilkS")
			(hide yes)
			(effects
				(font
					(size 1.27 1.27)
				)
				(justify mirror)
			)
		)
		(property "Value" ""
			(at 0 0 90)
			(layer "B.Fab")
			(effects
				(font
					(size 1.27 1.27)
				)
				(justify mirror)
			)
		)
		(duplicate_pad_numbers_are_jumpers no)
		(fp_poly
			(pts
				(xy -0.3048 -0.1016) (xy -0.3048 0.9906) (xy 0.3048 0.9906) (xy 0.3048 -0.1016)
			)
			(stroke
				(width 0)
				(type default)
			)
			(fill no)
			(layer "B.CrtYd")
		)
		(fp_line
			(start 0.3048 -0.1016)
			(end 0.3048 0.9906)
			(stroke
				(width 0.1)
				(type default)
			)
			(layer "B.Fab")
		)
		(fp_line
			(start -0.3048 -0.1016)
			(end 0.3048 -0.1016)
			(stroke
				(width 0.1)
				(type default)
			)
			(layer "B.Fab")
		)
		(fp_line
			(start 0.3048 0.9906)
			(end -0.3048 0.9906)
			(stroke
				(width 0.1)
				(type default)
			)
			(layer "B.Fab")
		)
		(fp_line
			(start -0.3048 0.9906)
			(end -0.3048 -0.1016)
			(stroke
				(width 0.1)
				(type default)
			)
			(layer "B.Fab")
		)
		(pad "1" smd rect
			(at 0 0 270)
			(size 0.508 0.508)
			(layers "B.Cu" "B.Mask" "B.Paste")
			(net "P3V3_STBY")
		)
		(pad "2" smd rect
			(at 0 0.889 270)
			(size 0.508 0.508)
			(layers "B.Cu" "B.Mask" "B.Paste")
			(net "GND")
		)
		(zone
			(layer "B.Cu")
			(hatch none 0.5)
			(connect_pads
				(clearance 0)
			)
			(min_thickness 0.25)
			(keepout
				(tracks allowed)
				(vias not_allowed)
				(pads allowed)
				(copperpour not_allowed)
				(footprints allowed)
			)
			(placement
				(enabled no)
				(sheetname "")
			)
			(fill
				(thermal_gap 0.5)
				(thermal_bridge_width 0.5)
				(island_removal_mode 0)
			)
			(polygon
				(pts
					(xy 493.32134 -123.32208) (xy 493.32134 -122.81408) (xy 493.70234 -122.81408) (xy 493.70234 -123.32208)
				)
			)
		)
		(zone
			(layer "B.Cu")
			(hatch none 0.5)
			(connect_pads
				(clearance 0)
			)
			(min_thickness 0.25)
			(keepout
				(tracks not_allowed)
				(vias allowed)
				(pads allowed)
				(copperpour not_allowed)
				(footprints allowed)
			)
			(placement
				(enabled no)
				(sheetname "")
			)
			(fill
				(thermal_gap 0.5)
				(thermal_bridge_width 0.5)
				(island_removal_mode 0)
			)
			(polygon
				(pts
					(xy 493.70234 -123.32208) (xy 493.70234 -122.81408) (xy 493.32134 -122.81408) (xy 493.32134 -123.32208)
				)
			)
		)
	)
	(footprint ""
		(layer "B.Cu")
		(at 107.8611 -149.8092 90)
		(property "Reference" "C5G104"
			(at -1.14681 0.76708 180)
			(unlocked yes)
			(layer "B.SilkS")
			(effects
				(font
					(size 0.7874 0.5842)
					(thickness 0.1524)
				)
				(justify mirror)
			)
		)
		(property "Value" ""
			(at 0 0 90)
			(layer "B.Fab")
			(effects
				(font
					(size 1.27 1.27)
				)
				(justify mirror)
			)
		)
		(duplicate_pad_numbers_are_jumpers no)
		(fp_rect
			(start -0.4953 -0.2032)
			(end 0.4953 1.6002)
			(stroke
				(width 0)
				(type default)
			)
			(fill no)
			(layer "B.CrtYd")
		)
		(fp_line
			(start 0.4953 -0.2032)
			(end -0.4953 -0.2032)
			(stroke
				(width 0.1)
				(type default)
			)
			(layer "B.Fab")
		)
		(fp_line
			(start -0.4953 -0.2032)
			(end -0.4953 1.6002)
			(stroke
				(width 0.1)
				(type default)
			)
			(layer "B.Fab")
		)
		(fp_line
			(start 0.4953 1.6002)
			(end 0.4953 -0.2032)
			(stroke
				(width 0.1)
				(type default)
			)
			(layer "B.Fab")
		)
		(fp_line
			(start -0.4953 1.6002)
			(end 0.4953 1.6002)
			(stroke
				(width 0.1)
				(type default)
			)
			(layer "B.Fab")
		)
		(pad "1" smd rect
			(at 0 0 270)
			(size 0.762 0.889)
			(layers "B.Cu" "B.Mask" "B.Paste")
			(net "PVDDQ_KLM")
		)
		(pad "2" smd rect
			(at 0 1.397 270)
			(size 0.762 0.889)
			(layers "B.Cu" "B.Mask" "B.Paste")
			(net "GND")
		)
		(zone
			(layer "B.Cu")
			(hatch none 0.5)
			(connect_pads
				(clearance 0)
			)
			(min_thickness 0.25)
			(keepout
				(tracks not_allowed)
				(vias allowed)
				(pads allowed)
				(copperpour not_allowed)
				(footprints allowed)
			)
			(placement
				(enabled no)
				(sheetname "")
			)
			(fill
				(thermal_gap 0.5)
				(thermal_bridge_width 0.5)
				(island_removal_mode 0)
			)
			(polygon
				(pts
					(xy 108.3056 -149.4282) (xy 108.8136 -149.4282) (xy 108.8136 -150.1902) (xy 108.3056 -150.1902)
				)
			)
		)
	)
	(footprint ""
		(layer "B.Cu")
		(at 375.519696 -62.277752)
		(property "Reference" "C2T1"
			(at 0 0 0)
			(layer "B.SilkS")
			(hide yes)
			(effects
				(font
					(size 1.27 1.27)
				)
				(justify mirror)
			)
		)
		(property "Value" ""
			(at 0 0 0)
			(layer "B.Fab")
			(effects
				(font
					(size 1.27 1.27)
				)
				(justify mirror)
			)
		)
		(duplicate_pad_numbers_are_jumpers no)
		(fp_poly
			(pts
				(xy -0.3048 -0.1016) (xy -0.3048 0.9906) (xy 0.3048 0.9906) (xy 0.3048 -0.1016)
			)
			(stroke
				(width 0)
				(type default)
			)
			(fill no)
			(layer "B.CrtYd")
		)
		(fp_line
			(start -0.3048 -0.1016)
			(end 0.3048 -0.1016)
			(stroke
				(width 0.1)
				(type default)
			)
			(layer "B.Fab")
		)
		(fp_line
			(start -0.3048 0.9906)
			(end -0.3048 -0.1016)
			(stroke
				(width 0.1)
				(type default)
			)
			(layer "B.Fab")
		)
		(fp_line
			(start 0.3048 -0.1016)
			(end 0.3048 0.9906)
			(stroke
				(width 0.1)
				(type default)
			)
			(layer "B.Fab")
		)
		(fp_line
			(start 0.3048 0.9906)
			(end -0.3048 0.9906)
			(stroke
				(width 0.1)
				(type default)
			)
			(layer "B.Fab")
		)
		(pad "1" smd rect
			(at 0 0 180)
			(size 0.508 0.508)
			(layers "B.Cu" "B.Mask" "B.Paste")
			(net "P3V3_STBY")
		)
		(pad "2" smd rect
			(at 0 0.889 180)
			(size 0.508 0.508)
			(layers "B.Cu" "B.Mask" "B.Paste")
			(net "GND")
		)
		(zone
			(layer "B.Cu")
			(hatch none 0.5)
			(connect_pads
				(clearance 0)
			)
			(min_thickness 0.25)
			(keepout
				(tracks allowed)
				(vias not_allowed)
				(pads allowed)
				(copperpour not_allowed)
				(footprints allowed)
			)
			(placement
				(enabled no)
				(sheetname "")
			)
			(fill
				(thermal_gap 0.5)
				(thermal_bridge_width 0.5)
				(island_removal_mode 0)
			)
			(polygon
				(pts
					(xy 375.773696 -62.023752) (xy 375.265696 -62.023752) (xy 375.265696 -61.642752) (xy 375.773696 -61.642752)
				)
			)
		)
		(zone
			(layer "B.Cu")
			(hatch none 0.5)
			(connect_pads
				(clearance 0)
			)
			(min_thickness 0.25)
			(keepout
				(tracks not_allowed)
				(vias allowed)
				(pads allowed)
				(copperpour not_allowed)
				(footprints allowed)
			)
			(placement
				(enabled no)
				(sheetname "")
			)
			(fill
				(thermal_gap 0.5)
				(thermal_bridge_width 0.5)
				(island_removal_mode 0)
			)
			(polygon
				(pts
					(xy 375.773696 -61.642752) (xy 375.265696 -61.642752) (xy 375.265696 -62.023752) (xy 375.773696 -62.023752)
				)
			)
		)
	)
	(footprint ""
		(layer "B.Cu")
		(at 379.476 -20.193 90)
		(property "Reference" "CN8F1"
			(at 0.8382 -0.67818 90)
			(unlocked yes)
			(layer "B.SilkS")
			(effects
				(font
					(size 0.4064 0.254)
					(thickness 0.1524)
				)
				(justify left mirror)
			)
		)
		(property "Value" ""
			(at 0 0 90)
			(layer "B.Fab")
			(effects
				(font
					(size 1.27 1.27)
				)
				(justify mirror)
			)
		)
		(duplicate_pad_numbers_are_jumpers no)
		(fp_poly
			(pts
				(xy -0.3048 -0.1016) (xy -0.3048 0.9906) (xy 0.3048 0.9906) (xy 0.3048 -0.1016)
			)
			(stroke
				(width 0)
				(type default)
			)
			(fill no)
			(layer "B.CrtYd")
		)
		(fp_line
			(start 0.3048 -0.1016)
			(end 0.3048 0.9906)
			(stroke
				(width 0.1)
				(type default)
			)
			(layer "B.Fab")
		)
		(fp_line
			(start -0.3048 -0.1016)
			(end 0.3048 -0.1016)
			(stroke
				(width 0.1)
				(type default)
			)
			(layer "B.Fab")
		)
		(fp_line
			(start 0.3048 0.9906)
			(end -0.3048 0.9906)
			(stroke
				(width 0.1)
				(type default)
			)
			(layer "B.Fab")
		)
		(fp_line
			(start -0.3048 0.9906)
			(end -0.3048 -0.1016)
			(stroke
				(width 0.1)
				(type default)
			)
			(layer "B.Fab")
		)
		(pad "1" smd rect
			(at 0 0 270)
			(size 0.508 0.508)
			(layers "B.Cu" "B.Mask" "B.Paste")
			(net "P3V3_STBY")
		)
		(pad "2" smd rect
			(at 0 0.889 270)
			(size 0.508 0.508)
			(layers "B.Cu" "B.Mask" "B.Paste")
			(net "GND")
		)
		(zone
			(layer "B.Cu")
			(hatch none 0.5)
			(connect_pads
				(clearance 0)
			)
			(min_thickness 0.25)
			(keepout
				(tracks allowed)
				(vias not_allowed)
				(pads allowed)
				(copperpour not_allowed)
				(footprints allowed)
			)
			(placement
				(enabled no)
				(sheetname "")
			)
			(fill
				(thermal_gap 0.5)
				(thermal_bridge_width 0.5)
				(island_removal_mode 0)
			)
			(polygon
				(pts
					(xy 379.73 -20.447) (xy 379.73 -19.939) (xy 380.111 -19.939) (xy 380.111 -20.447)
				)
			)
		)
		(zone
			(layer "B.Cu")
			(hatch none 0.5)
			(connect_pads
				(clearance 0)
			)
			(min_thickness 0.25)
			(keepout
				(tracks not_allowed)
				(vias allowed)
				(pads allowed)
				(copperpour not_allowed)
				(footprints allowed)
			)
			(placement
				(enabled no)
				(sheetname "")
			)
			(fill
				(thermal_gap 0.5)
				(thermal_bridge_width 0.5)
				(island_removal_mode 0)
			)
			(polygon
				(pts
					(xy 380.111 -20.447) (xy 380.111 -19.939) (xy 379.73 -19.939) (xy 379.73 -20.447)
				)
			)
		)
	)
	(footprint ""
		(layer "B.Cu")
		(at 351.507806 -60.368434)
		(property "Reference" "R2U27"
			(at 0 0 0)
			(layer "B.SilkS")
			(hide yes)
			(effects
				(font
					(size 1.27 1.27)
				)
				(justify mirror)
			)
		)
		(property "Value" ""
			(at 0 0 0)
			(layer "B.Fab")
			(effects
				(font
					(size 1.27 1.27)
				)
				(justify mirror)
			)
		)
		(duplicate_pad_numbers_are_jumpers no)
		(fp_poly
			(pts
				(xy 0.2794 -0.1016) (xy -0.2794 -0.1016) (xy -0.2794 0.9906) (xy 0.2794 0.9906)
			)
			(stroke
				(width 0)
				(type default)
			)
			(fill no)
			(layer "B.CrtYd")
		)
		(fp_line
			(start -0.2794 -0.1016)
			(end 0.2794 -0.1016)
			(stroke
				(width 0.1)
				(type default)
			)
			(layer "B.Fab")
		)
		(fp_line
			(start -0.2794 0.9906)
			(end -0.2794 -0.1016)
			(stroke
				(width 0.1)
				(type default)
			)
			(layer "B.Fab")
		)
		(fp_line
			(start 0.2794 -0.1016)
			(end 0.2794 0.9906)
			(stroke
				(width 0.1)
				(type default)
			)
			(layer "B.Fab")
		)
		(fp_line
			(start 0.2794 0.9906)
			(end -0.2794 0.9906)
			(stroke
				(width 0.1)
				(type default)
			)
			(layer "B.Fab")
		)
		(pad "1" smd rect
			(at 0 0 180)
			(size 0.508 0.508)
			(layers "B.Cu" "B.Mask" "B.Paste")
			(net "P3E_CPU0_PE1_SS_RXN<6>")
		)
		(pad "2" smd rect
			(at 0 0.889 180)
			(size 0.508 0.508)
			(layers "B.Cu" "B.Mask" "B.Paste")
			(net "P3E_CPU0_PE1_SS_R_RXN<6>")
		)
		(zone
			(layer "B.Cu")
			(hatch none 0.5)
			(connect_pads
				(clearance 0)
			)
			(min_thickness 0.25)
			(keepout
				(tracks allowed)
				(vias not_allowed)
				(pads allowed)
				(copperpour not_allowed)
				(footprints allowed)
			)
			(placement
				(enabled no)
				(sheetname "")
			)
			(fill
				(thermal_gap 0.5)
				(thermal_bridge_width 0.5)
				(island_removal_mode 0)
			)
			(polygon
				(pts
					(xy 351.761806 -60.114434) (xy 351.253806 -60.114434) (xy 351.253806 -59.733434) (xy 351.761806 -59.733434)
				)
			)
		)
		(zone
			(layer "B.Cu")
			(hatch none 0.5)
			(connect_pads
				(clearance 0)
			)
			(min_thickness 0.25)
			(keepout
				(tracks not_allowed)
				(vias allowed)
				(pads allowed)
				(copperpour not_allowed)
				(footprints allowed)
			)
			(placement
				(enabled no)
				(sheetname "")
			)
			(fill
				(thermal_gap 0.5)
				(thermal_bridge_width 0.5)
				(island_removal_mode 0)
			)
			(polygon
				(pts
					(xy 351.761806 -59.733434) (xy 351.253806 -59.733434) (xy 351.253806 -60.114434) (xy 351.761806 -60.114434)
				)
			)
		)
	)
	(footprint ""
		(layer "B.Cu")
		(at 470.8144 -15.3162)
		(property "Reference" "C2U19"
			(at 0 0 0)
			(layer "B.SilkS")
			(hide yes)
			(effects
				(font
					(size 1.27 1.27)
				)
				(justify mirror)
			)
		)
		(property "Value" ""
			(at 0 0 0)
			(layer "B.Fab")
			(effects
				(font
					(size 1.27 1.27)
				)
				(justify mirror)
			)
		)
		(duplicate_pad_numbers_are_jumpers no)
		(fp_rect
			(start 0.3048 -0.1016)
			(end -0.3048 0.9906)
			(stroke
				(width 0)
				(type default)
			)
			(fill no)
			(layer "B.CrtYd")
		)
		(fp_line
			(start -0.3048 -0.1016)
			(end 0.3048 -0.1016)
			(stroke
				(width 0.1)
				(type default)
			)
			(layer "B.Fab")
		)
		(fp_line
			(start -0.3048 0.9906)
			(end -0.3048 -0.1016)
			(stroke
				(width 0.1)
				(type default)
			)
			(layer "B.Fab")
		)
		(fp_line
			(start 0.3048 -0.1016)
			(end 0.3048 0.9906)
			(stroke
				(width 0.1)
				(type default)
			)
			(layer "B.Fab")
		)
		(fp_line
			(start 0.3048 0.9906)
			(end -0.3048 0.9906)
			(stroke
				(width 0.1)
				(type default)
			)
			(layer "B.Fab")
		)
		(pad "1" smd rect
			(at 0 0 180)
			(size 0.508 0.508)
			(layers "B.Cu" "B.Mask" "B.Paste")
			(net "P3V3")
		)
		(pad "2" smd rect
			(at 0 0.889 180)
			(size 0.508 0.508)
			(layers "B.Cu" "B.Mask" "B.Paste")
			(net "GND")
		)
		(zone
			(layer "B.Cu")
			(hatch none 0.5)
			(connect_pads
				(clearance 0)
			)
			(min_thickness 0.25)
			(keepout
				(tracks not_allowed)
				(vias allowed)
				(pads allowed)
				(copperpour not_allowed)
				(footprints allowed)
			)
			(placement
				(enabled no)
				(sheetname "")
			)
			(fill
				(thermal_gap 0.5)
				(thermal_bridge_width 0.5)
				(island_removal_mode 0)
			)
			(polygon
				(pts
					(xy 471.0684 -15.0622) (xy 470.5604 -15.0622) (xy 470.5604 -14.6812) (xy 471.0684 -14.6812)
				)
			)
		)
		(zone
			(layer "B.Cu")
			(hatch none 0.5)
			(connect_pads
				(clearance 0)
			)
			(min_thickness 0.25)
			(keepout
				(tracks allowed)
				(vias not_allowed)
				(pads allowed)
				(copperpour not_allowed)
				(footprints allowed)
			)
			(placement
				(enabled no)
				(sheetname "")
			)
			(fill
				(thermal_gap 0.5)
				(thermal_bridge_width 0.5)
				(island_removal_mode 0)
			)
			(polygon
				(pts
					(xy 471.0684 -15.0622) (xy 470.5604 -15.0622) (xy 470.5604 -14.6812) (xy 471.0684 -14.6812)
				)
			)
		)
	)
	(footprint ""
		(layer "B.Cu")
		(at 389.90651 -44.874688)
		(property "Reference" "Q2U1"
			(at 1.51765 0.54864 90)
			(unlocked yes)
			(layer "B.SilkS")
			(effects
				(font
					(size 0.7874 0.5842)
					(thickness 0.1524)
				)
				(justify left mirror)
			)
		)
		(property "Value" ""
			(at 0 0 0)
			(layer "B.Fab")
			(effects
				(font
					(size 1.27 1.27)
				)
				(justify mirror)
			)
		)
		(duplicate_pad_numbers_are_jumpers no)
		(fp_circle
			(center 0.508 -0.7874)
			(end 0.635 -0.7874)
			(stroke
				(width 0.254)
				(type default)
			)
			(fill no)
			(layer "B.SilkS")
		)
		(fp_poly
			(pts
				(xy -0.2159 1.7526) (xy -1.5621 1.7526) (xy -1.5621 -0.4572) (xy -0.2159 -0.4572)
			)
			(stroke
				(width 0)
				(type default)
			)
			(fill no)
			(layer "B.CrtYd")
		)
		(fp_line
			(start -1.5621 -0.45466)
			(end -0.2159 -0.45466)
			(stroke
				(width 0.1)
				(type default)
			)
			(layer "B.Fab")
		)
		(fp_line
			(start -1.5621 1.75514)
			(end -1.5621 -0.45466)
			(stroke
				(width 0.1)
				(type default)
			)
			(layer "B.Fab")
		)
		(fp_line
			(start -0.2159 -0.45466)
			(end -0.2159 1.75514)
			(stroke
				(width 0.1)
				(type default)
			)
			(layer "B.Fab")
		)
		(fp_line
			(start -0.2159 1.75514)
			(end -1.5621 1.75514)
			(stroke
				(width 0.1)
				(type default)
			)
			(layer "B.Fab")
		)
		(fp_circle
			(center 0.508 -0.7874)
			(end 0.635 -0.7874)
			(stroke
				(width 0.254)
				(type default)
			)
			(fill no)
			(layer "B.Fab")
		)
		(pad "1" smd rect
			(at 0 0 180)
			(size 1.016 0.381)
			(layers "B.Cu" "B.Mask" "B.Paste")
			(net "GND")
		)
		(pad "2" smd rect
			(at 0 0.65024 180)
			(size 1.016 0.381)
			(layers "B.Cu" "B.Mask" "B.Paste")
			(net "FM_SYS_THROTTLE_LVC3")
		)
		(pad "3" smd rect
			(at 0 1.30048 180)
			(size 1.016 0.381)
			(layers "B.Cu" "B.Mask" "B.Paste")
			(net "H_CPU0_MEMDEF_MEMHOT_G_N")
		)
		(pad "4" smd rect
			(at -1.778 1.30048 180)
			(size 1.016 0.381)
			(layers "B.Cu" "B.Mask" "B.Paste")
			(net "GND")
		)
		(pad "5" smd rect
			(at -1.778 0.65024 180)
			(size 1.016 0.381)
			(layers "B.Cu" "B.Mask" "B.Paste")
			(net "FM_SYS_THROTTLE_LVC3")
		)
		(pad "6" smd rect
			(at -1.778 0 180)
			(size 1.016 0.381)
			(layers "B.Cu" "B.Mask" "B.Paste")
			(net "H_CPU0_MEMABC_MEMHOT_G_N")
		)
		(zone
			(layer "B.Cu")
			(hatch none 0.5)
			(connect_pads
				(clearance 0)
			)
			(min_thickness 0.25)
			(keepout
				(tracks allowed)
				(vias not_allowed)
				(pads allowed)
				(copperpour not_allowed)
				(footprints allowed)
			)
			(placement
				(enabled no)
				(sheetname "")
			)
			(fill
				(thermal_gap 0.5)
				(thermal_bridge_width 0.5)
				(island_removal_mode 0)
			)
			(polygon
				(pts
					(xy 388.63651 -45.065188) (xy 387.62051 -45.065188) (xy 387.62051 -43.376088) (xy 388.63651 -43.376088)
				)
			)
		)
		(zone
			(layer "B.Cu")
			(hatch none 0.5)
			(connect_pads
				(clearance 0)
			)
			(min_thickness 0.25)
			(keepout
				(tracks allowed)
				(vias not_allowed)
				(pads allowed)
				(copperpour not_allowed)
				(footprints allowed)
			)
			(placement
				(enabled no)
				(sheetname "")
			)
			(fill
				(thermal_gap 0.5)
				(thermal_bridge_width 0.5)
				(island_removal_mode 0)
			)
			(polygon
				(pts
					(xy 390.41451 -45.065188) (xy 389.39851 -45.065188) (xy 389.39851 -43.376088) (xy 390.41451 -43.376088)
				)
			)
		)
	)
)
